# T6G (Grand Teton) — schematic netlist excerpt (pin names and nets, part order shuffled) for the footprints in the layout excerpt that follows; sources: Cadence DE-HDL packaged netlist, KiCad conversion of 04192023_DAF0TMB3IC0_F0TG_MB_C_brd_V02_OCP.brd

PC99  Q_CAP  0.1UF 25V 10% X7R  pkg 0402  page 201 : A = PVDDCR_CPU1_P0 ; B = GND
R6071  Q_RES  4.7K 5% EMPTY  pkg 0402LF  page 150 : A = P3V3_AUX ; B = PU_JTAG_DBP_BMC_PRDY_N

(kicad_pcb
	(version 20260206)
	(generator "pcbnew")
	(generator_version "10.0")
	(general
		(thickness 1.6)
		(legacy_teardrops no)
	)
	(paper "A4")
	(title_block
		(title "04192023_DAF0TMB3IC0_F0TG_MB_C_brd_V02_OCP.brd")
		(comment 1 "Grand Teton / footprints 4478-4479 of 8354")
	)
	(layers
		(0 "F.Cu" signal "TOP")
		(4 "In1.Cu" signal "GND")
		(6 "In2.Cu" signal "IN1")
		(8 "In3.Cu" signal "GND1")
		(10 "In4.Cu" signal "IN2")
		(12 "In5.Cu" signal "GND2")
		(14 "In6.Cu" signal "IN3")
		(16 "In7.Cu" signal "GND3")
		(18 "In8.Cu" signal "VCC")
		(20 "In9.Cu" signal "VCC1")
		(22 "In10.Cu" signal "GND4")
		(24 "In11.Cu" signal "IN4")
		(26 "In12.Cu" signal "GND5")
		(28 "In13.Cu" signal "IN5")
		(30 "In14.Cu" signal "GND6")
		(32 "In15.Cu" signal "IN6")
		(34 "In16.Cu" signal "GND7")
		(2 "B.Cu" signal "BOTTOM")
		(9 "F.Adhes" user "F.Adhesive")
		(11 "B.Adhes" user "B.Adhesive")
		(13 "F.Paste" user "Package Geometry/Pastemask Top")
		(15 "B.Paste" user "Package Geometry/Pastemask Bottom")
		(5 "F.SilkS" user "Ref Des/Silkscreen Top")
		(7 "B.SilkS" user "Ref Des/Silkscreen Bottom")
		(1 "F.Mask" user "Board Geometry/Soldermask Top")
		(3 "B.Mask" user "Board Geometry/Soldermask Bottom")
		(17 "Dwgs.User" user "User.Drawings")
		(19 "Cmts.User" user "User.Comments")
		(21 "Eco1.User" user "User.Eco1")
		(23 "Eco2.User" user "User.Eco2")
		(25 "Edge.Cuts" user "Board Geometry/Outline")
		(27 "Margin" user)
		(31 "F.CrtYd" user "Package Geometry/Place Bound Top")
		(29 "B.CrtYd" user "Package Geometry/Place Bound Bottom")
		(35 "F.Fab" user "Ref Des/Assembly Top")
		(33 "B.Fab" user "Ref Des/Assembly Bottom")
	)
	(footprint ""
		(layer "F.Cu")
		(at 147.877022 -21.506942 90)
		(property "Reference" "R6071"
			(at 0 0 90)
			(layer "F.SilkS")
			(hide yes)
			(effects
				(font
					(size 1.27 1.27)
				)
			)
		)
		(property "Value" ""
			(at 0 0 90)
			(layer "F.Fab")
			(effects
				(font
					(size 1.27 1.27)
				)
			)
		)
		(duplicate_pad_numbers_are_jumpers no)
		(fp_line
			(start 0.7874 -0.4064)
			(end 0.7874 0.4064)
			(stroke
				(width 0.1524)
				(type default)
			)
			(layer "F.SilkS")
		)
		(fp_line
			(start -0.7874 -0.4064)
			(end 0.7874 -0.4064)
			(stroke
				(width 0.1524)
				(type default)
			)
			(layer "F.SilkS")
		)
		(fp_line
			(start 0.7874 0.4064)
			(end -0.7874 0.4064)
			(stroke
				(width 0.1524)
				(type default)
			)
			(layer "F.SilkS")
		)
		(fp_line
			(start -0.7874 0.4064)
			(end -0.7874 -0.4064)
			(stroke
				(width 0.1524)
				(type default)
			)
			(layer "F.SilkS")
		)
		(fp_line
			(start -0.12065 -0.305054)
			(end -0.12065 -0.2794)
			(stroke
				(width 0.1)
				(type default)
			)
			(layer "F.Fab")
		)
		(fp_line
			(start -0.67945 -0.305054)
			(end -0.12065 -0.305054)
			(stroke
				(width 0.1)
				(type default)
			)
			(layer "F.Fab")
		)
		(fp_line
			(start 0.67945 -0.3048)
			(end 0.67945 0.3048)
			(stroke
				(width 0.1)
				(type default)
			)
			(layer "F.Fab")
		)
		(fp_line
			(start 0.12065 -0.3048)
			(end 0.67945 -0.3048)
			(stroke
				(width 0.1)
				(type default)
			)
			(layer "F.Fab")
		)
		(fp_line
			(start 0.12065 -0.2794)
			(end 0.12065 -0.3048)
			(stroke
				(width 0.1)
				(type default)
			)
			(layer "F.Fab")
		)
		(fp_line
			(start -0.12065 -0.2794)
			(end 0.12065 -0.2794)
			(stroke
				(width 0.1)
				(type default)
			)
			(layer "F.Fab")
		)
		(fp_line
			(start 0.120396 0.2794)
			(end -0.12065 0.2794)
			(stroke
				(width 0.1)
				(type default)
			)
			(layer "F.Fab")
		)
		(fp_line
			(start -0.12065 0.2794)
			(end -0.12065 0.3048)
			(stroke
				(width 0.1)
				(type default)
			)
			(layer "F.Fab")
		)
		(fp_line
			(start 0.67945 0.3048)
			(end 0.120396 0.3048)
			(stroke
				(width 0.1)
				(type default)
			)
			(layer "F.Fab")
		)
		(fp_line
			(start 0.120396 0.3048)
			(end 0.120396 0.2794)
			(stroke
				(width 0.1)
				(type default)
			)
			(layer "F.Fab")
		)
		(fp_line
			(start -0.12065 0.3048)
			(end -0.67945 0.3048)
			(stroke
				(width 0.1)
				(type default)
			)
			(layer "F.Fab")
		)
		(fp_line
			(start -0.67945 0.3048)
			(end -0.67945 -0.305054)
			(stroke
				(width 0.1)
				(type default)
			)
			(layer "F.Fab")
		)
		(pad "1" smd circle
			(at -0.40005 0 90)
			(size 0 0)
			(layers "F.Cu" "F.Mask" "F.Paste")
			(net "P3V3_AUX")
		)
		(pad "2" smd circle
			(at 0.40005 0 90)
			(size 0 0)
			(layers "F.Cu" "F.Mask" "F.Paste")
			(net "PU_JTAG_DBP_BMC_PRDY_N")
		)
	)
	(footprint ""
		(layer "F.Cu")
		(at 356.53726 -327.09231 -90)
		(property "Reference" "PC99"
			(at 0 0 270)
			(layer "F.SilkS")
			(hide yes)
			(effects
				(font
					(size 1.27 1.27)
				)
			)
		)
		(property "Value" ""
			(at 0 0 270)
			(layer "F.Fab")
			(effects
				(font
					(size 1.27 1.27)
				)
			)
		)
		(duplicate_pad_numbers_are_jumpers no)
		(fp_line
			(start -0.7874 0.4064)
			(end -0.7874 -0.4064)
			(stroke
				(width 0.1524)
				(type default)
			)
			(layer "F.SilkS")
		)
		(fp_line
			(start 0.7874 0.4064)
			(end -0.7874 0.4064)
			(stroke
				(width 0.1524)
				(type default)
			)
			(layer "F.SilkS")
		)
		(fp_line
			(start -0.7874 -0.4064)
			(end 0.7874 -0.4064)
			(stroke
				(width 0.1524)
				(type default)
			)
			(layer "F.SilkS")
		)
		(fp_line
			(start 0.7874 -0.4064)
			(end 0.7874 0.4064)
			(stroke
				(width 0.1524)
				(type default)
			)
			(layer "F.SilkS")
		)
		(fp_line
			(start -0.67945 0.3048)
			(end -0.67945 -0.305054)
			(stroke
				(width 0.1)
				(type default)
			)
			(layer "F.Fab")
		)
		(fp_line
			(start -0.12065 0.3048)
			(end -0.67945 0.3048)
			(stroke
				(width 0.1)
				(type default)
			)
			(layer "F.Fab")
		)
		(fp_line
			(start 0.120396 0.3048)
			(end 0.120396 0.2794)
			(stroke
				(width 0.1)
				(type default)
			)
			(layer "F.Fab")
		)
		(fp_line
			(start 0.67945 0.3048)
			(end 0.120396 0.3048)
			(stroke
				(width 0.1)
				(type default)
			)
			(layer "F.Fab")
		)
		(fp_line
			(start -0.12065 0.2794)
			(end -0.12065 0.3048)
			(stroke
				(width 0.1)
				(type default)
			)
			(layer "F.Fab")
		)
		(fp_line
			(start 0.120396 0.2794)
			(end -0.12065 0.2794)
			(stroke
				(width 0.1)
				(type default)
			)
			(layer "F.Fab")
		)
		(fp_line
			(start -0.12065 -0.2794)
			(end 0.12065 -0.2794)
			(stroke
				(width 0.1)
				(type default)
			)
			(layer "F.Fab")
		)
		(fp_line
			(start 0.12065 -0.2794)
			(end 0.12065 -0.3048)
			(stroke
				(width 0.1)
				(type default)
			)
			(layer "F.Fab")
		)
		(fp_line
			(start 0.12065 -0.3048)
			(end 0.67945 -0.3048)
			(stroke
				(width 0.1)
				(type default)
			)
			(layer "F.Fab")
		)
		(fp_line
			(start 0.67945 -0.3048)
			(end 0.67945 0.3048)
			(stroke
				(width 0.1)
				(type default)
			)
			(layer "F.Fab")
		)
		(fp_line
			(start -0.67945 -0.305054)
			(end -0.12065 -0.305054)
			(stroke
				(width 0.1)
				(type default)
			)
			(layer "F.Fab")
		)
		(fp_line
			(start -0.12065 -0.305054)
			(end -0.12065 -0.2794)
			(stroke
				(width 0.1)
				(type default)
			)
			(layer "F.Fab")
		)
		(pad "1" smd circle
			(at -0.40005 0 270)
			(size 0 0)
			(layers "F.Cu" "F.Mask" "F.Paste")
			(net "PVDDCR_CPU1_P0")
		)
		(pad "2" smd circle
			(at 0.40005 0 270)
			(size 0 0)
			(layers "F.Cu" "F.Mask" "F.Paste")
			(net "GND")
		)
	)
)
